(kicad_pcb
	(version 20260206)
	(generator "pcbnew")
	(generator_version "10.0")
	(general
		(thickness 1.6)
		(legacy_teardrops no)
	)
	(paper "A4")
	(title_block
		(title "04192023_DAF0TMB3IC0_F0TG_MB_C_brd_V02_OCP.brd")
		(comment 1 "Grand Teton / footprints 517-524 of 8354")
	)
	(layers
		(0 "F.Cu" signal "TOP")
		(4 "In1.Cu" signal "GND")
		(6 "In2.Cu" signal "IN1")
		(8 "In3.Cu" signal "GND1")
		(10 "In4.Cu" signal "IN2")
		(12 "In5.Cu" signal "GND2")
		(14 "In6.Cu" signal "IN3")
		(16 "In7.Cu" signal "GND3")
		(18 "In8.Cu" signal "VCC")
		(20 "In9.Cu" signal "VCC1")
		(22 "In10.Cu" signal "GND4")
		(24 "In11.Cu" signal "IN4")
		(26 "In12.Cu" signal "GND5")
		(28 "In13.Cu" signal "IN5")
		(30 "In14.Cu" signal "GND6")
		(32 "In15.Cu" signal "IN6")
		(34 "In16.Cu" signal "GND7")
		(2 "B.Cu" signal "BOTTOM")
		(9 "F.Adhes" user "F.Adhesive")
		(11 "B.Adhes" user "B.Adhesive")
		(13 "F.Paste" user "Package Geometry/Pastemask Top")
		(15 "B.Paste" user "Package Geometry/Pastemask Bottom")
		(5 "F.SilkS" user "Ref Des/Silkscreen Top")
		(7 "B.SilkS" user "Ref Des/Silkscreen Bottom")
		(1 "F.Mask" user "Board Geometry/Soldermask Top")
		(3 "B.Mask" user "Board Geometry/Soldermask Bottom")
		(17 "Dwgs.User" user "User.Drawings")
		(19 "Cmts.User" user "User.Comments")
		(21 "Eco1.User" user "User.Eco1")
		(23 "Eco2.User" user "User.Eco2")
		(25 "Edge.Cuts" user "Board Geometry/Outline")
		(27 "Margin" user)
		(31 "F.CrtYd" user "Package Geometry/Place Bound Top")
		(29 "B.CrtYd" user "Package Geometry/Place Bound Bottom")
		(35 "F.Fab" user "Ref Des/Assembly Top")
		(33 "B.Fab" user "Ref Des/Assembly Bottom")
	)
	(footprint ""
		(layer "F.Cu")
		(at 169.349166 -416.929316 90)
		(property "Reference" "R812"
			(at 0 0 90)
			(layer "F.SilkS")
			(hide yes)
			(effects
				(font
					(size 1.27 1.27)
				)
			)
		)
		(property "Value" ""
			(at 0 0 90)
			(layer "F.Fab")
			(effects
				(font
					(size 1.27 1.27)
				)
			)
		)
		(duplicate_pad_numbers_are_jumpers no)
		(fp_line
			(start 0.32512 -0.175006)
			(end 0.32512 0.175006)
			(stroke
				(width 0.1)
				(type default)
			)
			(layer "F.Fab")
		)
		(fp_line
			(start -0.32512 -0.175006)
			(end 0.32512 -0.175006)
			(stroke
				(width 0.1)
				(type default)
			)
			(layer "F.Fab")
		)
		(fp_line
			(start 0.32512 0.175006)
			(end -0.32512 0.175006)
			(stroke
				(width 0.1)
				(type default)
			)
			(layer "F.Fab")
		)
		(fp_line
			(start -0.32512 0.175006)
			(end -0.32512 -0.175006)
			(stroke
				(width 0.1)
				(type default)
			)
			(layer "F.Fab")
		)
		(pad "1" smd rect
			(at -0.2667 0 90)
			(size 0.3048 0.381)
			(layers "F.Cu" "F.Mask" "F.Paste")
			(net "P1V8_CPU1_RT_1D")
		)
		(pad "2" smd rect
			(at 0.2667 0 270)
			(size 0.3048 0.381)
			(layers "F.Cu" "F.Mask" "F.Paste")
			(net "SMB_RT_CPU1_P3_ROM_R_SCL")
		)
	)
	(footprint ""
		(layer "F.Cu")
		(at 27.561794 -393.317984 -90)
		(property "Reference" "PC6640"
			(at 0 0 270)
			(layer "F.SilkS")
			(hide yes)
			(effects
				(font
					(size 1.27 1.27)
				)
			)
		)
		(property "Value" ""
			(at 0 0 270)
			(layer "F.Fab")
			(effects
				(font
					(size 1.27 1.27)
				)
			)
		)
		(duplicate_pad_numbers_are_jumpers no)
		(fp_line
			(start -0.7874 0.4064)
			(end -0.7874 -0.4064)
			(stroke
				(width 0.1524)
				(type default)
			)
			(layer "F.SilkS")
		)
		(fp_line
			(start 0.7874 0.4064)
			(end -0.7874 0.4064)
			(stroke
				(width 0.1524)
				(type default)
			)
			(layer "F.SilkS")
		)
		(fp_line
			(start -0.7874 -0.4064)
			(end 0.7874 -0.4064)
			(stroke
				(width 0.1524)
				(type default)
			)
			(layer "F.SilkS")
		)
		(fp_line
			(start 0.7874 -0.4064)
			(end 0.7874 0.4064)
			(stroke
				(width 0.1524)
				(type default)
			)
			(layer "F.SilkS")
		)
		(fp_line
			(start -0.67945 0.3048)
			(end -0.67945 -0.305054)
			(stroke
				(width 0.1)
				(type default)
			)
			(layer "F.Fab")
		)
		(fp_line
			(start -0.12065 0.3048)
			(end -0.67945 0.3048)
			(stroke
				(width 0.1)
				(type default)
			)
			(layer "F.Fab")
		)
		(fp_line
			(start 0.120396 0.3048)
			(end 0.120396 0.2794)
			(stroke
				(width 0.1)
				(type default)
			)
			(layer "F.Fab")
		)
		(fp_line
			(start 0.67945 0.3048)
			(end 0.120396 0.3048)
			(stroke
				(width 0.1)
				(type default)
			)
			(layer "F.Fab")
		)
		(fp_line
			(start -0.12065 0.2794)
			(end -0.12065 0.3048)
			(stroke
				(width 0.1)
				(type default)
			)
			(layer "F.Fab")
		)
		(fp_line
			(start 0.120396 0.2794)
			(end -0.12065 0.2794)
			(stroke
				(width 0.1)
				(type default)
			)
			(layer "F.Fab")
		)
		(fp_line
			(start -0.12065 -0.2794)
			(end 0.12065 -0.2794)
			(stroke
				(width 0.1)
				(type default)
			)
			(layer "F.Fab")
		)
		(fp_line
			(start 0.12065 -0.2794)
			(end 0.12065 -0.3048)
			(stroke
				(width 0.1)
				(type default)
			)
			(layer "F.Fab")
		)
		(fp_line
			(start 0.12065 -0.3048)
			(end 0.67945 -0.3048)
			(stroke
				(width 0.1)
				(type default)
			)
			(layer "F.Fab")
		)
		(fp_line
			(start 0.67945 -0.3048)
			(end 0.67945 0.3048)
			(stroke
				(width 0.1)
				(type default)
			)
			(layer "F.Fab")
		)
		(fp_line
			(start -0.67945 -0.305054)
			(end -0.12065 -0.305054)
			(stroke
				(width 0.1)
				(type default)
			)
			(layer "F.Fab")
		)
		(fp_line
			(start -0.12065 -0.305054)
			(end -0.12065 -0.2794)
			(stroke
				(width 0.1)
				(type default)
			)
			(layer "F.Fab")
		)
		(pad "1" smd circle
			(at -0.40005 0 270)
			(size 0 0)
			(layers "F.Cu" "F.Mask" "F.Paste")
			(net "SW_P0V9_RETIMER_CPU1_BOOT2_RC")
		)
		(pad "2" smd circle
			(at 0.40005 0 270)
			(size 0 0)
			(layers "F.Cu" "F.Mask" "F.Paste")
			(net "SW_P0V9_RETIMER_CPU1_PH2")
		)
	)
	(footprint ""
		(layer "F.Cu")
		(at 419.391084 -423.777664 90)
		(property "Reference" "R683"
			(at 0 0 90)
			(layer "F.SilkS")
			(hide yes)
			(effects
				(font
					(size 1.27 1.27)
				)
			)
		)
		(property "Value" ""
			(at 0 0 90)
			(layer "F.Fab")
			(effects
				(font
					(size 1.27 1.27)
				)
			)
		)
		(duplicate_pad_numbers_are_jumpers no)
		(fp_line
			(start 0.32512 -0.175006)
			(end 0.32512 0.175006)
			(stroke
				(width 0.1)
				(type default)
			)
			(layer "F.Fab")
		)
		(fp_line
			(start -0.32512 -0.175006)
			(end 0.32512 -0.175006)
			(stroke
				(width 0.1)
				(type default)
			)
			(layer "F.Fab")
		)
		(fp_line
			(start 0.32512 0.175006)
			(end -0.32512 0.175006)
			(stroke
				(width 0.1)
				(type default)
			)
			(layer "F.Fab")
		)
		(fp_line
			(start -0.32512 0.175006)
			(end -0.32512 -0.175006)
			(stroke
				(width 0.1)
				(type default)
			)
			(layer "F.Fab")
		)
		(pad "1" smd rect
			(at -0.2667 0 90)
			(size 0.3048 0.381)
			(layers "F.Cu" "F.Mask" "F.Paste")
			(net "SMB_RT_CPU0_P2_ROM_R_SDA")
		)
		(pad "2" smd rect
			(at 0.2667 0 270)
			(size 0.3048 0.381)
			(layers "F.Cu" "F.Mask" "F.Paste")
			(net "SMB_RT_CPU0_P2_ROM_SDA")
		)
	)
	(footprint ""
		(layer "F.Cu")
		(at 413.766 -98.425 90)
		(property "Reference" "R8092"
			(at 0 0 90)
			(layer "F.SilkS")
			(hide yes)
			(effects
				(font
					(size 1.27 1.27)
				)
			)
		)
		(property "Value" ""
			(at 0 0 90)
			(layer "F.Fab")
			(effects
				(font
					(size 1.27 1.27)
				)
			)
		)
		(duplicate_pad_numbers_are_jumpers no)
		(fp_line
			(start 0.7874 -0.4064)
			(end 0.7874 0.4064)
			(stroke
				(width 0.1524)
				(type default)
			)
			(layer "F.SilkS")
		)
		(fp_line
			(start -0.7874 -0.4064)
			(end 0.7874 -0.4064)
			(stroke
				(width 0.1524)
				(type default)
			)
			(layer "F.SilkS")
		)
		(fp_line
			(start 0.7874 0.4064)
			(end -0.7874 0.4064)
			(stroke
				(width 0.1524)
				(type default)
			)
			(layer "F.SilkS")
		)
		(fp_line
			(start -0.7874 0.4064)
			(end -0.7874 -0.4064)
			(stroke
				(width 0.1524)
				(type default)
			)
			(layer "F.SilkS")
		)
		(fp_line
			(start -0.12065 -0.305054)
			(end -0.12065 -0.2794)
			(stroke
				(width 0.1)
				(type default)
			)
			(layer "F.Fab")
		)
		(fp_line
			(start -0.67945 -0.305054)
			(end -0.12065 -0.305054)
			(stroke
				(width 0.1)
				(type default)
			)
			(layer "F.Fab")
		)
		(fp_line
			(start 0.67945 -0.3048)
			(end 0.67945 0.3048)
			(stroke
				(width 0.1)
				(type default)
			)
			(layer "F.Fab")
		)
		(fp_line
			(start 0.12065 -0.3048)
			(end 0.67945 -0.3048)
			(stroke
				(width 0.1)
				(type default)
			)
			(layer "F.Fab")
		)
		(fp_line
			(start 0.12065 -0.2794)
			(end 0.12065 -0.3048)
			(stroke
				(width 0.1)
				(type default)
			)
			(layer "F.Fab")
		)
		(fp_line
			(start -0.12065 -0.2794)
			(end 0.12065 -0.2794)
			(stroke
				(width 0.1)
				(type default)
			)
			(layer "F.Fab")
		)
		(fp_line
			(start 0.120396 0.2794)
			(end -0.12065 0.2794)
			(stroke
				(width 0.1)
				(type default)
			)
			(layer "F.Fab")
		)
		(fp_line
			(start -0.12065 0.2794)
			(end -0.12065 0.3048)
			(stroke
				(width 0.1)
				(type default)
			)
			(layer "F.Fab")
		)
		(fp_line
			(start 0.67945 0.3048)
			(end 0.120396 0.3048)
			(stroke
				(width 0.1)
				(type default)
			)
			(layer "F.Fab")
		)
		(fp_line
			(start 0.120396 0.3048)
			(end 0.120396 0.2794)
			(stroke
				(width 0.1)
				(type default)
			)
			(layer "F.Fab")
		)
		(fp_line
			(start -0.12065 0.3048)
			(end -0.67945 0.3048)
			(stroke
				(width 0.1)
				(type default)
			)
			(layer "F.Fab")
		)
		(fp_line
			(start -0.67945 0.3048)
			(end -0.67945 -0.305054)
			(stroke
				(width 0.1)
				(type default)
			)
			(layer "F.Fab")
		)
		(pad "1" smd circle
			(at -0.40005 0 90)
			(size 0 0)
			(layers "F.Cu" "F.Mask" "F.Paste")
			(net "P3V3_OCP_SFF_R")
		)
		(pad "2" smd circle
			(at 0.40005 0 90)
			(size 0 0)
			(layers "F.Cu" "F.Mask" "F.Paste")
			(net "OCP_V3_1_P3V3_R1_PWRGD")
		)
	)
	(footprint ""
		(layer "F.Cu")
		(at 432.636676 -94.938342)
		(property "Reference" "R3603"
			(at 0 0 0)
			(layer "F.SilkS")
			(hide yes)
			(effects
				(font
					(size 1.27 1.27)
				)
			)
		)
		(property "Value" ""
			(at 0 0 0)
			(layer "F.Fab")
			(effects
				(font
					(size 1.27 1.27)
				)
			)
		)
		(duplicate_pad_numbers_are_jumpers no)
		(fp_line
			(start -0.7874 -0.4064)
			(end 0.7874 -0.4064)
			(stroke
				(width 0.1524)
				(type default)
			)
			(layer "F.SilkS")
		)
		(fp_line
			(start -0.7874 0.4064)
			(end -0.7874 -0.4064)
			(stroke
				(width 0.1524)
				(type default)
			)
			(layer "F.SilkS")
		)
		(fp_line
			(start 0.7874 -0.4064)
			(end 0.7874 0.4064)
			(stroke
				(width 0.1524)
				(type default)
			)
			(layer "F.SilkS")
		)
		(fp_line
			(start 0.7874 0.4064)
			(end -0.7874 0.4064)
			(stroke
				(width 0.1524)
				(type default)
			)
			(layer "F.SilkS")
		)
		(fp_line
			(start -0.67945 -0.305054)
			(end -0.12065 -0.305054)
			(stroke
				(width 0.1)
				(type default)
			)
			(layer "F.Fab")
		)
		(fp_line
			(start -0.67945 0.3048)
			(end -0.67945 -0.305054)
			(stroke
				(width 0.1)
				(type default)
			)
			(layer "F.Fab")
		)
		(fp_line
			(start -0.12065 -0.305054)
			(end -0.12065 -0.2794)
			(stroke
				(width 0.1)
				(type default)
			)
			(layer "F.Fab")
		)
		(fp_line
			(start -0.12065 -0.2794)
			(end 0.12065 -0.2794)
			(stroke
				(width 0.1)
				(type default)
			)
			(layer "F.Fab")
		)
		(fp_line
			(start -0.12065 0.2794)
			(end -0.12065 0.3048)
			(stroke
				(width 0.1)
				(type default)
			)
			(layer "F.Fab")
		)
		(fp_line
			(start -0.12065 0.3048)
			(end -0.67945 0.3048)
			(stroke
				(width 0.1)
				(type default)
			)
			(layer "F.Fab")
		)
		(fp_line
			(start 0.120396 0.2794)
			(end -0.12065 0.2794)
			(stroke
				(width 0.1)
				(type default)
			)
			(layer "F.Fab")
		)
		(fp_line
			(start 0.120396 0.3048)
			(end 0.120396 0.2794)
			(stroke
				(width 0.1)
				(type default)
			)
			(layer "F.Fab")
		)
		(fp_line
			(start 0.12065 -0.3048)
			(end 0.67945 -0.3048)
			(stroke
				(width 0.1)
				(type default)
			)
			(layer "F.Fab")
		)
		(fp_line
			(start 0.12065 -0.2794)
			(end 0.12065 -0.3048)
			(stroke
				(width 0.1)
				(type default)
			)
			(layer "F.Fab")
		)
		(fp_line
			(start 0.67945 -0.3048)
			(end 0.67945 0.3048)
			(stroke
				(width 0.1)
				(type default)
			)
			(layer "F.Fab")
		)
		(fp_line
			(start 0.67945 0.3048)
			(end 0.120396 0.3048)
			(stroke
				(width 0.1)
				(type default)
			)
			(layer "F.Fab")
		)
		(pad "1" smd circle
			(at -0.40005 0)
			(size 0 0)
			(layers "F.Cu" "F.Mask" "F.Paste")
			(net "P3V3_OCP_SFF")
		)
		(pad "2" smd circle
			(at 0.40005 0)
			(size 0 0)
			(layers "F.Cu" "F.Mask" "F.Paste")
			(net "VSENSE_P3V3_INA230_1_INN")
		)
	)
	(footprint ""
		(layer "F.Cu")
		(at 155.605226 -408.517344 -90)
		(property "Reference" "C6719"
			(at 0 0 270)
			(layer "F.SilkS")
			(hide yes)
			(effects
				(font
					(size 1.27 1.27)
				)
			)
		)
		(property "Value" ""
			(at 0 0 270)
			(layer "F.Fab")
			(effects
				(font
					(size 1.27 1.27)
				)
			)
		)
		(duplicate_pad_numbers_are_jumpers no)
		(fp_line
			(start -0.299974 0.150114)
			(end -0.299974 -0.150114)
			(stroke
				(width 0.1)
				(type default)
			)
			(layer "F.Fab")
		)
		(fp_line
			(start 0.299974 0.150114)
			(end -0.299974 0.150114)
			(stroke
				(width 0.1)
				(type default)
			)
			(layer "F.Fab")
		)
		(fp_line
			(start -0.299974 -0.150114)
			(end 0.299974 -0.150114)
			(stroke
				(width 0.1)
				(type default)
			)
			(layer "F.Fab")
		)
		(fp_line
			(start 0.299974 -0.150114)
			(end 0.299974 0.150114)
			(stroke
				(width 0.1)
				(type default)
			)
			(layer "F.Fab")
		)
		(pad "1" smd rect
			(at -0.2667 0 270)
			(size 0.3048 0.381)
			(layers "F.Cu" "F.Mask" "F.Paste")
			(net "P5E_CPU1_P2_TX_BUF_C_DP<13>")
		)
		(pad "2" smd rect
			(at 0.2667 0 270)
			(size 0.3048 0.381)
			(layers "F.Cu" "F.Mask" "F.Paste")
			(net "P5E_CPU1_P2_TX_BUF_DP<13>")
		)
	)
	(footprint ""
		(layer "F.Cu")
		(at 11.665458 -423.821098 180)
		(property "Reference" "R6172"
			(at 0 0 180)
			(layer "F.SilkS")
			(hide yes)
			(effects
				(font
					(size 1.27 1.27)
				)
			)
		)
		(property "Value" ""
			(at 0 0 180)
			(layer "F.Fab")
			(effects
				(font
					(size 1.27 1.27)
				)
			)
		)
		(duplicate_pad_numbers_are_jumpers no)
		(fp_line
			(start 0.7874 0.4064)
			(end -0.7874 0.4064)
			(stroke
				(width 0.1524)
				(type default)
			)
			(layer "F.SilkS")
		)
		(fp_line
			(start 0.7874 -0.4064)
			(end 0.7874 0.4064)
			(stroke
				(width 0.1524)
				(type default)
			)
			(layer "F.SilkS")
		)
		(fp_line
			(start -0.7874 0.4064)
			(end -0.7874 -0.4064)
			(stroke
				(width 0.1524)
				(type default)
			)
			(layer "F.SilkS")
		)
		(fp_line
			(start -0.7874 -0.4064)
			(end 0.7874 -0.4064)
			(stroke
				(width 0.1524)
				(type default)
			)
			(layer "F.SilkS")
		)
		(fp_line
			(start 0.67945 0.3048)
			(end 0.120396 0.3048)
			(stroke
				(width 0.1)
				(type default)
			)
			(layer "F.Fab")
		)
		(fp_line
			(start 0.67945 -0.3048)
			(end 0.67945 0.3048)
			(stroke
				(width 0.1)
				(type default)
			)
			(layer "F.Fab")
		)
		(fp_line
			(start 0.12065 -0.2794)
			(end 0.12065 -0.3048)
			(stroke
				(width 0.1)
				(type default)
			)
			(layer "F.Fab")
		)
		(fp_line
			(start 0.12065 -0.3048)
			(end 0.67945 -0.3048)
			(stroke
				(width 0.1)
				(type default)
			)
			(layer "F.Fab")
		)
		(fp_line
			(start 0.120396 0.3048)
			(end 0.120396 0.2794)
			(stroke
				(width 0.1)
				(type default)
			)
			(layer "F.Fab")
		)
		(fp_line
			(start 0.120396 0.2794)
			(end -0.12065 0.2794)
			(stroke
				(width 0.1)
				(type default)
			)
			(layer "F.Fab")
		)
		(fp_line
			(start -0.12065 0.3048)
			(end -0.67945 0.3048)
			(stroke
				(width 0.1)
				(type default)
			)
			(layer "F.Fab")
		)
		(fp_line
			(start -0.12065 0.2794)
			(end -0.12065 0.3048)
			(stroke
				(width 0.1)
				(type default)
			)
			(layer "F.Fab")
		)
		(fp_line
			(start -0.12065 -0.2794)
			(end 0.12065 -0.2794)
			(stroke
				(width 0.1)
				(type default)
			)
			(layer "F.Fab")
		)
		(fp_line
			(start -0.12065 -0.305054)
			(end -0.12065 -0.2794)
			(stroke
				(width 0.1)
				(type default)
			)
			(layer "F.Fab")
		)
		(fp_line
			(start -0.67945 0.3048)
			(end -0.67945 -0.305054)
			(stroke
				(width 0.1)
				(type default)
			)
			(layer "F.Fab")
		)
		(fp_line
			(start -0.67945 -0.305054)
			(end -0.12065 -0.305054)
			(stroke
				(width 0.1)
				(type default)
			)
			(layer "F.Fab")
		)
		(pad "1" smd circle
			(at -0.40005 0 180)
			(size 0 0)
			(layers "F.Cu" "F.Mask" "F.Paste")
			(net "FM_P2E_BUF2_EQA1")
		)
		(pad "2" smd circle
			(at 0.40005 0 180)
			(size 0 0)
			(layers "F.Cu" "F.Mask" "F.Paste")
			(net "GND")
		)
	)
	(footprint ""
		(layer "F.Cu")
		(at 101.044502 -370.57203 -90)
		(property "Reference" "C715"
			(at 0 0 270)
			(layer "F.SilkS")
			(hide yes)
			(effects
				(font
					(size 1.27 1.27)
				)
			)
		)
		(property "Value" ""
			(at 0 0 270)
			(layer "F.Fab")
			(effects
				(font
					(size 1.27 1.27)
				)
			)
		)
		(duplicate_pad_numbers_are_jumpers no)
		(fp_line
			(start -0.299974 0.150114)
			(end -0.299974 -0.150114)
			(stroke
				(width 0.1)
				(type default)
			)
			(layer "F.Fab")
		)
		(fp_line
			(start 0.299974 0.150114)
			(end -0.299974 0.150114)
			(stroke
				(width 0.1)
				(type default)
			)
			(layer "F.Fab")
		)
		(fp_line
			(start -0.299974 -0.150114)
			(end 0.299974 -0.150114)
			(stroke
				(width 0.1)
				(type default)
			)
			(layer "F.Fab")
		)
		(fp_line
			(start 0.299974 -0.150114)
			(end 0.299974 0.150114)
			(stroke
				(width 0.1)
				(type default)
			)
			(layer "F.Fab")
		)
		(pad "1" smd rect
			(at -0.2667 0 270)
			(size 0.3048 0.381)
			(layers "F.Cu" "F.Mask" "F.Paste")
			(net "P5E_CPU1_P1_TX_C_DP<13>")
		)
		(pad "2" smd rect
			(at 0.2667 0 270)
			(size 0.3048 0.381)
			(layers "F.Cu" "F.Mask" "F.Paste")
			(net "P5E_CPU1_P1_TX_DP<13>")
		)
	)
)
